(kicad_pcb
	(version 20260206)
	(generator "pcbnew")
	(generator_version "10.0")
	(general
		(thickness 1.6)
		(legacy_teardrops no)
	)
	(paper "A4")
	(title_block
		(title "v1-chassis-manager — T6M_CM_d_v01_1031_1645.brd")
		(comment 1 "Open CloudServer (Microsoft) / footprints 372-381 of 2512")
	)
	(layers
		(0 "F.Cu" signal "TOP")
		(4 "In1.Cu" signal "GND1")
		(6 "In2.Cu" signal "IN1")
		(8 "In3.Cu" signal "VCC1")
		(10 "In4.Cu" signal "VCC2")
		(12 "In5.Cu" signal "GND2")
		(14 "In6.Cu" signal "IN2")
		(16 "In7.Cu" signal "IN3")
		(18 "In8.Cu" signal "GND3")
		(2 "B.Cu" signal "BOTTOM")
		(9 "F.Adhes" user "F.Adhesive")
		(11 "B.Adhes" user "B.Adhesive")
		(13 "F.Paste" user "Package Geometry/Pastemask Top")
		(15 "B.Paste" user "Package Geometry/Pastemask Bottom")
		(5 "F.SilkS" user "Ref Des/Silkscreen Top")
		(7 "B.SilkS" user "Ref Des/Silkscreen Bottom")
		(1 "F.Mask" user "Board Geometry/Soldermask Top")
		(3 "B.Mask" user "Board Geometry/Soldermask Bottom")
		(17 "Dwgs.User" user "User.Drawings")
		(19 "Cmts.User" user "User.Comments")
		(21 "Eco1.User" user "User.Eco1")
		(23 "Eco2.User" user "User.Eco2")
		(25 "Edge.Cuts" user "Board Geometry/Outline")
		(27 "Margin" user)
		(31 "F.CrtYd" user "Package Geometry/Place Bound Top")
		(29 "B.CrtYd" user "Package Geometry/Place Bound Bottom")
		(35 "F.Fab" user "Ref Des/Assembly Top")
		(33 "B.Fab" user "Ref Des/Assembly Bottom")
	)
	(footprint ""
		(layer "F.Cu")
		(at 140.90396 -121.324624 90)
		(property "Reference" "L1"
			(at 2.205482 -0.094742 90)
			(unlocked yes)
			(layer "F.SilkS")
			(effects
				(font
					(size 0.7874 0.5842)
					(thickness 0.1524)
				)
				(justify left)
			)
		)
		(property "Value" ""
			(at 0 0 90)
			(layer "F.Fab")
			(effects
				(font
					(size 1.27 1.27)
				)
			)
		)
		(duplicate_pad_numbers_are_jumpers no)
		(fp_line
			(start -1.905 -0.8636)
			(end 1.905 -0.8636)
			(stroke
				(width 0.1524)
				(type default)
			)
			(layer "F.SilkS")
		)
		(fp_line
			(start 1.905 0.8382)
			(end 1.905 -0.8382)
			(stroke
				(width 0.1524)
				(type default)
			)
			(layer "F.SilkS")
		)
		(fp_line
			(start 0.127 0.8382)
			(end 0.127 -0.8382)
			(stroke
				(width 0.1524)
				(type default)
			)
			(layer "F.SilkS")
		)
		(fp_line
			(start -0.127 0.8382)
			(end -0.127 -0.8382)
			(stroke
				(width 0.1524)
				(type default)
			)
			(layer "F.SilkS")
		)
		(fp_line
			(start -1.905 0.8382)
			(end -1.905 -0.8382)
			(stroke
				(width 0.1524)
				(type default)
			)
			(layer "F.SilkS")
		)
		(fp_line
			(start 1.905 0.8636)
			(end -1.905 0.8636)
			(stroke
				(width 0.1524)
				(type default)
			)
			(layer "F.SilkS")
		)
		(fp_rect
			(start -1.524 0.7112)
			(end 1.524 -0.7366)
			(stroke
				(width 0)
				(type default)
			)
			(fill no)
			(layer "F.CrtYd")
		)
		(pad "1" smd rect
			(at 0.94996 0 90)
			(size 1.1176 1.3716)
			(layers "F.Cu" "F.Mask" "F.Paste")
			(net "P1V5_CLK_NODE1_R")
		)
		(pad "2" smd rect
			(at -0.94996 0 90)
			(size 1.1176 1.3716)
			(layers "F.Cu" "F.Mask" "F.Paste")
			(net "P1V5_CLK_NODE1")
		)
	)
	(footprint ""
		(layer "F.Cu")
		(at 112.73663 -129.84734 90)
		(property "Reference" "PR43"
			(at -2.08026 1.034796 90)
			(unlocked yes)
			(layer "F.SilkS")
			(effects
				(font
					(size 0.7874 0.5842)
					(thickness 0.1524)
				)
				(justify left)
			)
		)
		(property "Value" ""
			(at 0 0 90)
			(layer "F.Fab")
			(effects
				(font
					(size 1.27 1.27)
				)
			)
		)
		(duplicate_pad_numbers_are_jumpers no)
		(fp_line
			(start 0.7874 -0.4064)
			(end 0.7874 0.4064)
			(stroke
				(width 0.1524)
				(type default)
			)
			(layer "F.SilkS")
		)
		(fp_line
			(start -0.7874 -0.4064)
			(end 0.7874 -0.4064)
			(stroke
				(width 0.1524)
				(type default)
			)
			(layer "F.SilkS")
		)
		(fp_line
			(start 0.7874 0.4064)
			(end -0.7874 0.4064)
			(stroke
				(width 0.1524)
				(type default)
			)
			(layer "F.SilkS")
		)
		(fp_line
			(start -0.7874 0.4064)
			(end -0.7874 -0.4064)
			(stroke
				(width 0.1524)
				(type default)
			)
			(layer "F.SilkS")
		)
		(fp_poly
			(pts
				(xy -0.508 0.2794) (xy -0.508 0.2286) (xy -0.635 0.2286) (xy -0.635 -0.254) (xy -0.5334 -0.254)
				(xy -0.5334 -0.2794) (xy 0.5334 -0.2794) (xy 0.5334 -0.254) (xy 0.635 -0.254) (xy 0.635 0.254) (xy 0.5334 0.254)
				(xy 0.5334 0.2794)
			)
			(stroke
				(width 0)
				(type default)
			)
			(fill no)
			(layer "F.CrtYd")
		)
		(pad "1" smd rect
			(at 0.40005 0 90)
			(size 0.4572 0.508)
			(layers "F.Cu" "F.Mask" "F.Paste")
			(net "VR_PVCCP_NODE1_TONSET_R")
		)
		(pad "2" smd rect
			(at -0.40005 0 90)
			(size 0.4572 0.508)
			(layers "F.Cu" "F.Mask" "F.Paste")
			(net "SW_VR_PVCCP_NODE1_VIN_FLT")
		)
	)
	(footprint ""
		(layer "F.Cu")
		(at 80.845152 -133.211062 -90)
		(property "Reference" "D31"
			(at 5.319268 1.866646 90)
			(unlocked yes)
			(layer "F.SilkS")
			(effects
				(font
					(size 0.7874 0.5842)
					(thickness 0.1524)
				)
				(justify left)
			)
		)
		(property "Value" ""
			(at 0 0 270)
			(layer "F.Fab")
			(effects
				(font
					(size 1.27 1.27)
				)
			)
		)
		(duplicate_pad_numbers_are_jumpers no)
		(fp_line
			(start -1.3208 0.5588)
			(end -1.3208 -0.5588)
			(stroke
				(width 0.1524)
				(type default)
			)
			(layer "F.SilkS")
		)
		(fp_line
			(start 1.3208 0.5588)
			(end -1.3208 0.5588)
			(stroke
				(width 0.1524)
				(type default)
			)
			(layer "F.SilkS")
		)
		(fp_line
			(start 1.6256 0.5588)
			(end 1.6256 -0.5588)
			(stroke
				(width 0.1524)
				(type default)
			)
			(layer "F.SilkS")
		)
		(fp_line
			(start 1.778 0.5588)
			(end 1.3208 0.5588)
			(stroke
				(width 0.1524)
				(type default)
			)
			(layer "F.SilkS")
		)
		(fp_line
			(start -1.3208 -0.5588)
			(end 1.3208 -0.5588)
			(stroke
				(width 0.1524)
				(type default)
			)
			(layer "F.SilkS")
		)
		(fp_line
			(start 1.3208 -0.5588)
			(end 1.3208 0.5588)
			(stroke
				(width 0.1524)
				(type default)
			)
			(layer "F.SilkS")
		)
		(fp_line
			(start 1.4732 -0.5588)
			(end 1.4732 0.5588)
			(stroke
				(width 0.1524)
				(type default)
			)
			(layer "F.SilkS")
		)
		(fp_line
			(start 1.778 -0.5588)
			(end 1.778 0.5588)
			(stroke
				(width 0.1524)
				(type default)
			)
			(layer "F.SilkS")
		)
		(fp_line
			(start 1.778 -0.5588)
			(end 1.3208 -0.5588)
			(stroke
				(width 0.1524)
				(type default)
			)
			(layer "F.SilkS")
		)
		(fp_circle
			(center 2.4384 0)
			(end 2.4384 -0.413512)
			(stroke
				(width 0.1524)
				(type default)
			)
			(fill no)
			(layer "F.SilkS")
		)
		(fp_rect
			(start -1.1684 0.508)
			(end 1.1684 -0.508)
			(stroke
				(width 0)
				(type default)
			)
			(fill no)
			(layer "F.CrtYd")
		)
		(fp_text user "-"
			(at 1.199642 0.946404 270)
			(unlocked yes)
			(layer "F.SilkS")
			(effects
				(font
					(size 0.7874 0.5842)
					(thickness 0.1524)
				)
				(justify left)
			)
		)
		(pad "A" smd rect
			(at -0.750062 0 270)
			(size 0.8128 0.8128)
			(layers "F.Cu" "F.Mask" "F.Paste")
			(net "P3V3_NODE1")
		)
		(pad "C" smd rect
			(at 0.750062 0 270)
			(size 0.8128 0.8128)
			(layers "F.Cu" "F.Mask" "F.Paste")
			(net "N53313646")
		)
	)
	(footprint ""
		(layer "F.Cu")
		(at 118.47576 -188.126624 -90)
		(property "Reference" "R985"
			(at -4.912868 -0.016002 90)
			(unlocked yes)
			(layer "F.SilkS")
			(effects
				(font
					(size 0.7874 0.5842)
					(thickness 0.1524)
				)
				(justify left)
			)
		)
		(property "Value" ""
			(at 0 0 270)
			(layer "F.Fab")
			(effects
				(font
					(size 1.27 1.27)
				)
			)
		)
		(duplicate_pad_numbers_are_jumpers no)
		(fp_line
			(start -0.7874 0.4064)
			(end -0.7874 -0.4064)
			(stroke
				(width 0.1524)
				(type default)
			)
			(layer "F.SilkS")
		)
		(fp_line
			(start 0.7874 0.4064)
			(end -0.7874 0.4064)
			(stroke
				(width 0.1524)
				(type default)
			)
			(layer "F.SilkS")
		)
		(fp_line
			(start -0.7874 -0.4064)
			(end 0.7874 -0.4064)
			(stroke
				(width 0.1524)
				(type default)
			)
			(layer "F.SilkS")
		)
		(fp_line
			(start 0.7874 -0.4064)
			(end 0.7874 0.4064)
			(stroke
				(width 0.1524)
				(type default)
			)
			(layer "F.SilkS")
		)
		(fp_poly
			(pts
				(xy -0.508 0.2794) (xy -0.508 0.2286) (xy -0.635 0.2286) (xy -0.635 -0.254) (xy -0.5334 -0.254)
				(xy -0.5334 -0.2794) (xy 0.5334 -0.2794) (xy 0.5334 -0.254) (xy 0.635 -0.254) (xy 0.635 0.254) (xy 0.5334 0.254)
				(xy 0.5334 0.2794)
			)
			(stroke
				(width 0)
				(type default)
			)
			(fill no)
			(layer "F.CrtYd")
		)
		(pad "1" smd rect
			(at 0.40005 0 270)
			(size 0.4572 0.508)
			(layers "F.Cu" "F.Mask" "F.Paste")
			(net "UART_T8_NODE2_RXD")
		)
		(pad "2" smd rect
			(at -0.40005 0 270)
			(size 0.4572 0.508)
			(layers "F.Cu" "F.Mask" "F.Paste")
			(net "UART_T8_NODE2_RXD_R")
		)
	)
	(footprint ""
		(layer "F.Cu")
		(at 154.252168 -172.67555 -90)
		(property "Reference" "C912"
			(at 3.873754 0.049276 90)
			(unlocked yes)
			(layer "F.SilkS")
			(effects
				(font
					(size 0.7874 0.5842)
					(thickness 0.1524)
				)
				(justify left)
			)
		)
		(property "Value" ""
			(at 0 0 270)
			(layer "F.Fab")
			(effects
				(font
					(size 1.27 1.27)
				)
			)
		)
		(duplicate_pad_numbers_are_jumpers no)
		(fp_line
			(start -0.7874 0.4064)
			(end -0.7874 -0.4064)
			(stroke
				(width 0.1524)
				(type default)
			)
			(layer "F.SilkS")
		)
		(fp_line
			(start 0.7874 0.4064)
			(end -0.7874 0.4064)
			(stroke
				(width 0.1524)
				(type default)
			)
			(layer "F.SilkS")
		)
		(fp_line
			(start 0 0.381)
			(end 0 -0.381)
			(stroke
				(width 0.1524)
				(type default)
			)
			(layer "F.SilkS")
		)
		(fp_line
			(start -0.7874 -0.4064)
			(end 0.7874 -0.4064)
			(stroke
				(width 0.1524)
				(type default)
			)
			(layer "F.SilkS")
		)
		(fp_line
			(start 0.7874 -0.4064)
			(end 0.7874 0.4064)
			(stroke
				(width 0.1524)
				(type default)
			)
			(layer "F.SilkS")
		)
		(fp_poly
			(pts
				(xy -0.5334 0.254) (xy -0.635 0.254) (xy -0.635 0.2286) (xy -0.635 -0.254) (xy -0.5334 -0.254) (xy -0.5334 -0.2794)
				(xy 0.5334 -0.2794) (xy 0.5334 -0.254) (xy 0.635 -0.254) (xy 0.635 0.254) (xy 0.5334 0.254) (xy 0.5334 0.2794)
				(xy -0.508 0.2794) (xy -0.5334 0.2794)
			)
			(stroke
				(width 0)
				(type default)
			)
			(fill no)
			(layer "F.CrtYd")
		)
		(pad "1" smd rect
			(at 0.40005 0 270)
			(size 0.4572 0.508)
			(layers "F.Cu" "F.Mask" "F.Paste")
			(net "N54365601")
		)
		(pad "2" smd rect
			(at -0.40005 0 270)
			(size 0.4572 0.508)
			(layers "F.Cu" "F.Mask" "F.Paste")
			(net "N54365603")
		)
	)
	(footprint ""
		(layer "F.Cu")
		(at 59.260486 -121.044462 -90)
		(property "Reference" "R340"
			(at 4.642612 -8.471916 90)
			(unlocked yes)
			(layer "F.SilkS")
			(effects
				(font
					(size 0.7874 0.5842)
					(thickness 0.1524)
				)
				(justify left)
			)
		)
		(property "Value" ""
			(at 0 0 270)
			(layer "F.Fab")
			(effects
				(font
					(size 1.27 1.27)
				)
			)
		)
		(duplicate_pad_numbers_are_jumpers no)
		(fp_line
			(start -0.7874 0.4064)
			(end -0.7874 -0.4064)
			(stroke
				(width 0.1524)
				(type default)
			)
			(layer "F.SilkS")
		)
		(fp_line
			(start 0.7874 0.4064)
			(end -0.7874 0.4064)
			(stroke
				(width 0.1524)
				(type default)
			)
			(layer "F.SilkS")
		)
		(fp_line
			(start -0.7874 -0.4064)
			(end 0.7874 -0.4064)
			(stroke
				(width 0.1524)
				(type default)
			)
			(layer "F.SilkS")
		)
		(fp_line
			(start 0.7874 -0.4064)
			(end 0.7874 0.4064)
			(stroke
				(width 0.1524)
				(type default)
			)
			(layer "F.SilkS")
		)
		(fp_poly
			(pts
				(xy -0.508 0.2794) (xy -0.508 0.2286) (xy -0.635 0.2286) (xy -0.635 -0.254) (xy -0.5334 -0.254)
				(xy -0.5334 -0.2794) (xy 0.5334 -0.2794) (xy 0.5334 -0.254) (xy 0.635 -0.254) (xy 0.635 0.254) (xy 0.5334 0.254)
				(xy 0.5334 0.2794)
			)
			(stroke
				(width 0)
				(type default)
			)
			(fill no)
			(layer "F.CrtYd")
		)
		(pad "1" smd rect
			(at 0.40005 0 270)
			(size 0.4572 0.508)
			(layers "F.Cu" "F.Mask" "F.Paste")
			(net "P3V3_NODE1")
		)
		(pad "2" smd rect
			(at -0.40005 0 270)
			(size 0.4572 0.508)
			(layers "F.Cu" "F.Mask" "F.Paste")
			(net "BMC_ROMD0")
		)
	)
	(footprint ""
		(layer "F.Cu")
		(at 105.191814 -110.95482 180)
		(property "Reference" "PC107"
			(at 5.79247 -0.103886 0)
			(unlocked yes)
			(layer "F.SilkS")
			(effects
				(font
					(size 0.7874 0.5842)
					(thickness 0.1524)
				)
				(justify left)
			)
		)
		(property "Value" ""
			(at 0 0 180)
			(layer "F.Fab")
			(effects
				(font
					(size 1.27 1.27)
				)
			)
		)
		(duplicate_pad_numbers_are_jumpers no)
		(fp_line
			(start 1.905 0.8636)
			(end -1.905 0.8636)
			(stroke
				(width 0.1524)
				(type default)
			)
			(layer "F.SilkS")
		)
		(fp_line
			(start 1.905 -0.8636)
			(end 1.905 0.8636)
			(stroke
				(width 0.1524)
				(type default)
			)
			(layer "F.SilkS")
		)
		(fp_line
			(start 0 0.8382)
			(end 0 -0.8382)
			(stroke
				(width 0.1524)
				(type default)
			)
			(layer "F.SilkS")
		)
		(fp_line
			(start -1.905 0.8636)
			(end -1.905 -0.8636)
			(stroke
				(width 0.1524)
				(type default)
			)
			(layer "F.SilkS")
		)
		(fp_line
			(start -1.905 -0.8636)
			(end 1.905 -0.8636)
			(stroke
				(width 0.1524)
				(type default)
			)
			(layer "F.SilkS")
		)
		(fp_rect
			(start -1.524 0.7366)
			(end 1.524 -0.7366)
			(stroke
				(width 0)
				(type default)
			)
			(fill no)
			(layer "F.CrtYd")
		)
		(pad "1" smd rect
			(at 0.94996 0 180)
			(size 1.1176 1.3716)
			(layers "F.Cu" "F.Mask" "F.Paste")
			(net "GND")
		)
		(pad "2" smd rect
			(at -0.94996 0 180)
			(size 1.1176 1.3716)
			(layers "F.Cu" "F.Mask" "F.Paste")
			(net "PV_VCCP_NODE1")
		)
	)
	(footprint ""
		(layer "F.Cu")
		(at 139.36218 -76.485496 180)
		(property "Reference" "R506"
			(at -0.939038 1.9685 0)
			(unlocked yes)
			(layer "F.SilkS")
			(effects
				(font
					(size 0.7874 0.5842)
					(thickness 0.1524)
				)
				(justify left)
			)
		)
		(property "Value" ""
			(at 0 0 180)
			(layer "F.Fab")
			(effects
				(font
					(size 1.27 1.27)
				)
			)
		)
		(duplicate_pad_numbers_are_jumpers no)
		(fp_line
			(start 0.7874 0.4064)
			(end -0.7874 0.4064)
			(stroke
				(width 0.1524)
				(type default)
			)
			(layer "F.SilkS")
		)
		(fp_line
			(start 0.7874 -0.4064)
			(end 0.7874 0.4064)
			(stroke
				(width 0.1524)
				(type default)
			)
			(layer "F.SilkS")
		)
		(fp_line
			(start -0.7874 0.4064)
			(end -0.7874 -0.4064)
			(stroke
				(width 0.1524)
				(type default)
			)
			(layer "F.SilkS")
		)
		(fp_line
			(start -0.7874 -0.4064)
			(end 0.7874 -0.4064)
			(stroke
				(width 0.1524)
				(type default)
			)
			(layer "F.SilkS")
		)
		(fp_poly
			(pts
				(xy -0.508 0.2794) (xy -0.508 0.2286) (xy -0.635 0.2286) (xy -0.635 -0.254) (xy -0.5334 -0.254)
				(xy -0.5334 -0.2794) (xy 0.5334 -0.2794) (xy 0.5334 -0.254) (xy 0.635 -0.254) (xy 0.635 0.254) (xy 0.5334 0.254)
				(xy 0.5334 0.2794)
			)
			(stroke
				(width 0)
				(type default)
			)
			(fill no)
			(layer "F.CrtYd")
		)
		(pad "1" smd rect
			(at 0.40005 0 180)
			(size 0.4572 0.508)
			(layers "F.Cu" "F.Mask" "F.Paste")
			(net "SATA_SPI_DO_NODE1")
		)
		(pad "2" smd rect
			(at -0.40005 0 180)
			(size 0.4572 0.508)
			(layers "F.Cu" "F.Mask" "F.Paste")
			(net "SATA_SPI_DO_NODE1_R")
		)
	)
	(footprint ""
		(layer "F.Cu")
		(at 132.32257 -26.569416 -90)
		(property "Reference" "R1146"
			(at 5.325618 -0.117348 90)
			(unlocked yes)
			(layer "F.SilkS")
			(effects
				(font
					(size 0.7874 0.5842)
					(thickness 0.1524)
				)
				(justify left)
			)
		)
		(property "Value" ""
			(at 0 0 270)
			(layer "F.Fab")
			(effects
				(font
					(size 1.27 1.27)
				)
			)
		)
		(duplicate_pad_numbers_are_jumpers no)
		(fp_line
			(start -0.7874 0.4064)
			(end -0.7874 -0.4064)
			(stroke
				(width 0.1524)
				(type default)
			)
			(layer "F.SilkS")
		)
		(fp_line
			(start 0.7874 0.4064)
			(end -0.7874 0.4064)
			(stroke
				(width 0.1524)
				(type default)
			)
			(layer "F.SilkS")
		)
		(fp_line
			(start -0.7874 -0.4064)
			(end 0.7874 -0.4064)
			(stroke
				(width 0.1524)
				(type default)
			)
			(layer "F.SilkS")
		)
		(fp_line
			(start 0.7874 -0.4064)
			(end 0.7874 0.4064)
			(stroke
				(width 0.1524)
				(type default)
			)
			(layer "F.SilkS")
		)
		(fp_poly
			(pts
				(xy -0.508 0.2794) (xy -0.508 0.2286) (xy -0.635 0.2286) (xy -0.635 -0.254) (xy -0.5334 -0.254)
				(xy -0.5334 -0.2794) (xy 0.5334 -0.2794) (xy 0.5334 -0.254) (xy 0.635 -0.254) (xy 0.635 0.254) (xy 0.5334 0.254)
				(xy 0.5334 0.2794)
			)
			(stroke
				(width 0)
				(type default)
			)
			(fill no)
			(layer "F.CrtYd")
		)
		(pad "1" smd rect
			(at 0.40005 0 270)
			(size 0.4572 0.508)
			(layers "F.Cu" "F.Mask" "F.Paste")
			(net "P3V3_STB_NODE1")
		)
		(pad "2" smd rect
			(at -0.40005 0 270)
			(size 0.4572 0.508)
			(layers "F.Cu" "F.Mask" "F.Paste")
			(net "SIO_PIN81")
		)
	)
	(footprint ""
		(layer "F.Cu")
		(at 188.849 -126.1872 180)
		(property "Reference" "R1269"
			(at -6.477 -18.89887 0)
			(unlocked yes)
			(layer "F.SilkS")
			(effects
				(font
					(size 0.7874 0.5842)
					(thickness 0.1524)
				)
				(justify left)
			)
		)
		(property "Value" ""
			(at 0 0 180)
			(layer "F.Fab")
			(effects
				(font
					(size 1.27 1.27)
				)
			)
		)
		(duplicate_pad_numbers_are_jumpers no)
		(fp_line
			(start 0.7874 0.4064)
			(end -0.7874 0.4064)
			(stroke
				(width 0.1524)
				(type default)
			)
			(layer "F.SilkS")
		)
		(fp_line
			(start 0.7874 -0.4064)
			(end 0.7874 0.4064)
			(stroke
				(width 0.1524)
				(type default)
			)
			(layer "F.SilkS")
		)
		(fp_line
			(start -0.7874 0.4064)
			(end -0.7874 -0.4064)
			(stroke
				(width 0.1524)
				(type default)
			)
			(layer "F.SilkS")
		)
		(fp_line
			(start -0.7874 -0.4064)
			(end 0.7874 -0.4064)
			(stroke
				(width 0.1524)
				(type default)
			)
			(layer "F.SilkS")
		)
		(fp_poly
			(pts
				(xy -0.508 0.2794) (xy -0.508 0.2286) (xy -0.635 0.2286) (xy -0.635 -0.254) (xy -0.5334 -0.254)
				(xy -0.5334 -0.2794) (xy 0.5334 -0.2794) (xy 0.5334 -0.254) (xy 0.635 -0.254) (xy 0.635 0.254) (xy 0.5334 0.254)
				(xy 0.5334 0.2794)
			)
			(stroke
				(width 0)
				(type default)
			)
			(fill no)
			(layer "F.CrtYd")
		)
		(pad "1" smd rect
			(at 0.40005 0 180)
			(size 0.4572 0.508)
			(layers "F.Cu" "F.Mask" "F.Paste")
			(net "SIO_JTAG_CPLD1_TMS")
		)
		(pad "2" smd rect
			(at -0.40005 0 180)
			(size 0.4572 0.508)
			(layers "F.Cu" "F.Mask" "F.Paste")
			(net "GND")
		)
	)
)
